(kicad_pcb
	(version 20260206)
	(generator "pcbnew")
	(generator_version "10.0")
	(general
		(thickness 1.6)
		(legacy_teardrops no)
	)
	(paper "A4")
	(title_block
		(title "timecard-production-celestica-r4006 — R4006-B0001-02_R01.brd")
		(comment 1 "Time Appliance Project (Time Card) / footprints 208-210 of 1113")
	)
	(layers
		(0 "F.Cu" signal "TOP")
		(4 "In1.Cu" signal "L02_GND1")
		(6 "In2.Cu" signal "L03_SIG1")
		(8 "In3.Cu" signal "L04_GND2")
		(10 "In4.Cu" signal "L05_VCC1")
		(12 "In5.Cu" signal "L06_VCC2")
		(14 "In6.Cu" signal "L07_GND3")
		(16 "In7.Cu" signal "L08_SIG2")
		(18 "In8.Cu" signal "L09_GND4")
		(2 "B.Cu" signal "BOTTOM")
		(9 "F.Adhes" user "F.Adhesive")
		(11 "B.Adhes" user "B.Adhesive")
		(13 "F.Paste" user "Package Geometry/Pastemask Top")
		(15 "B.Paste" user "Package Geometry/Pastemask Bottom")
		(5 "F.SilkS" user "Ref Des/Silkscreen Top")
		(7 "B.SilkS" user "Ref Des/Silkscreen Bottom")
		(1 "F.Mask" user "Board Geometry/Soldermask Top")
		(3 "B.Mask" user "Board Geometry/Soldermask Bottom")
		(17 "Dwgs.User" user "User.Drawings")
		(19 "Cmts.User" user "User.Comments")
		(21 "Eco1.User" user "User.Eco1")
		(23 "Eco2.User" user "User.Eco2")
		(25 "Edge.Cuts" user "Board Geometry/Outline")
		(27 "Margin" user)
		(31 "F.CrtYd" user "Package Geometry/Place Bound Top")
		(29 "B.CrtYd" user "Package Geometry/Place Bound Bottom")
		(35 "F.Fab" user "Ref Des/Assembly Top")
		(33 "B.Fab" user "Ref Des/Assembly Bottom")
	)
	(footprint ""
		(layer "F.Cu")
		(at 6.249924 -87.1601 -90)
		(property "Reference" "J13"
			(at -3.60553 1.677924 0)
			(unlocked yes)
			(layer "F.SilkS")
			(effects
				(font
					(size 0.7874 0.5842)
					(thickness 0.1524)
				)
			)
		)
		(property "Value" ""
			(at 0 0 270)
			(layer "F.Fab")
			(effects
				(font
					(size 1.27 1.27)
				)
			)
		)
		(property "Device Type" "CONN_USB_14P_GH4_F_RA_TH-G200-A"
			(at 0.389636 9.511792 270)
			(unlocked yes)
			(layer "F.Fab")
			(hide yes)
			(effects
				(font
					(size 0.7874 0.5842)
					(thickness 0.000001)
				)
			)
		)
		(property "User Part Number" "PARTNUM*"
			(at 0.389636 10.705592 270)
			(unlocked yes)
			(layer "Cmts.User")
			(hide yes)
			(effects
				(font
					(size 0.7874 0.5842)
					(thickness 0.000001)
				)
			)
		)
		(duplicate_pad_numbers_are_jumpers no)
		(fp_line
			(start -2.838704 8.402828)
			(end -2.838704 -6.854952)
			(stroke
				(width 0.1)
				(type default)
			)
			(layer "F.SilkS")
		)
		(fp_line
			(start 3.61823 8.402828)
			(end -2.838704 8.402828)
			(stroke
				(width 0.1)
				(type default)
			)
			(layer "F.SilkS")
		)
		(fp_line
			(start -2.838704 -6.854952)
			(end 3.61823 -6.854952)
			(stroke
				(width 0.1)
				(type default)
			)
			(layer "F.SilkS")
		)
		(fp_line
			(start 3.61823 -6.854952)
			(end 3.61823 8.402828)
			(stroke
				(width 0.1)
				(type default)
			)
			(layer "F.SilkS")
		)
		(fp_poly
			(pts
				(arc
					(start 0.77978 0.145288)
					(mid 0.77978 0.754888)
					(end 0.77978 0.145288)
				)
			)
			(stroke
				(width 0)
				(type default)
			)
			(fill yes)
			(layer "F.Paste")
		)
		(fp_poly
			(pts
				(arc
					(start 0 -0.3048)
					(mid 0 0.3048)
					(end 0 -0.3048)
				)
			)
			(stroke
				(width 0)
				(type default)
			)
			(fill yes)
			(layer "F.Paste")
		)
		(fp_poly
			(pts
				(arc
					(start 0.77978 -0.754888)
					(mid 0.77978 -0.145288)
					(end 0.77978 -0.754888)
				)
			)
			(stroke
				(width 0)
				(type default)
			)
			(fill yes)
			(layer "F.Paste")
		)
		(fp_poly
			(pts
				(arc
					(start 0 -1.204976)
					(mid 0 -0.595376)
					(end 0 -1.204976)
				)
			)
			(stroke
				(width 0)
				(type default)
			)
			(fill yes)
			(layer "F.Paste")
		)
		(fp_poly
			(pts
				(arc
					(start 0.77978 -1.655064)
					(mid 0.77978 -1.045464)
					(end 0.77978 -1.655064)
				)
			)
			(stroke
				(width 0)
				(type default)
			)
			(fill yes)
			(layer "F.Paste")
		)
		(fp_poly
			(pts
				(arc
					(start 0 -2.105152)
					(mid 0 -1.495552)
					(end 0 -2.105152)
				)
			)
			(stroke
				(width 0)
				(type default)
			)
			(fill yes)
			(layer "F.Paste")
		)
		(fp_poly
			(pts
				(arc
					(start 0.77978 -2.55524)
					(mid 0.77978 -1.94564)
					(end 0.77978 -2.55524)
				)
			)
			(stroke
				(width 0)
				(type default)
			)
			(fill yes)
			(layer "F.Paste")
		)
		(fp_poly
			(pts
				(arc
					(start 0 -3.005328)
					(mid 0 -2.395728)
					(end 0 -3.005328)
				)
			)
			(stroke
				(width 0)
				(type default)
			)
			(fill yes)
			(layer "F.Paste")
		)
		(fp_poly
			(pts
				(arc
					(start 0.77978 -3.455416)
					(mid 0.77978 -2.845816)
					(end 0.77978 -3.455416)
				)
			)
			(stroke
				(width 0)
				(type default)
			)
			(fill yes)
			(layer "F.Paste")
		)
		(fp_poly
			(pts
				(arc
					(start 0 -3.905504)
					(mid 0 -3.295904)
					(end 0 -3.905504)
				)
			)
			(stroke
				(width 0)
				(type default)
			)
			(fill yes)
			(layer "F.Paste")
		)
		(fp_poly
			(pts
				(arc
					(start 0.77978 -4.355592)
					(mid 0.77978 -3.745992)
					(end 0.77978 -4.355592)
				)
			)
			(stroke
				(width 0)
				(type default)
			)
			(fill yes)
			(layer "F.Paste")
		)
		(fp_poly
			(pts
				(arc
					(start 0 -4.80568)
					(mid 0 -4.19608)
					(end 0 -4.80568)
				)
			)
			(stroke
				(width 0)
				(type default)
			)
			(fill yes)
			(layer "F.Paste")
		)
		(fp_poly
			(pts
				(arc
					(start 0.77978 -5.255768)
					(mid 0.77978 -4.646168)
					(end 0.77978 -5.255768)
				)
			)
			(stroke
				(width 0)
				(type default)
			)
			(fill yes)
			(layer "F.Paste")
		)
		(fp_poly
			(pts
				(arc
					(start 0 -5.705856)
					(mid 0 -5.096256)
					(end 0 -5.705856)
				)
			)
			(stroke
				(width 0)
				(type default)
			)
			(fill yes)
			(layer "F.Paste")
		)
		(fp_poly
			(pts
				(arc
					(start -0.59563 0.456946)
					(mid -1.04013 0.901446)
					(end -1.48463 0.456946)
				)
				(arc
					(start -1.48463 -0.559054)
					(mid -1.04013 -1.003554)
					(end -0.59563 -0.559054)
				)
			)
			(stroke
				(width 0)
				(type default)
			)
			(fill yes)
			(layer "F.Paste")
		)
		(fp_poly
			(pts
				(arc
					(start 2.26441 0.456946)
					(mid 1.81991 0.901446)
					(end 1.37541 0.456946)
				)
				(arc
					(start 1.37541 -0.559054)
					(mid 1.81991 -1.003554)
					(end 2.26441 -0.559054)
				)
			)
			(stroke
				(width 0)
				(type default)
			)
			(fill yes)
			(layer "F.Paste")
		)
		(fp_poly
			(pts
				(arc
					(start -1.695704 -4.343146)
					(mid -2.140204 -3.898646)
					(end -2.584704 -4.343146)
				)
				(arc
					(start -2.584704 -5.359146)
					(mid -2.140204 -5.803646)
					(end -1.695704 -5.359146)
				)
			)
			(stroke
				(width 0)
				(type default)
			)
			(fill yes)
			(layer "F.Paste")
		)
		(fp_poly
			(pts
				(arc
					(start 3.36423 -4.343146)
					(mid 2.91973 -3.898646)
					(end 2.47523 -4.343146)
				)
				(arc
					(start 2.47523 -5.359146)
					(mid 2.91973 -5.803646)
					(end 3.36423 -5.359146)
				)
			)
			(stroke
				(width 0)
				(type default)
			)
			(fill yes)
			(layer "F.Paste")
		)
		(fp_rect
			(start -7.664704 5.981446)
			(end 8.44423 -10.883646)
			(stroke
				(width 0)
				(type default)
			)
			(fill no)
			(layer "B.CrtYd")
		)
		(fp_rect
			(start -3.092704 8.656828)
			(end 3.87223 -7.108952)
			(stroke
				(width 0)
				(type default)
			)
			(fill no)
			(layer "F.CrtYd")
		)
		(fp_line
			(start -1.59004 8.148828)
			(end -1.59004 -6.600952)
			(stroke
				(width 0.1)
				(type default)
			)
			(layer "F.Fab")
		)
		(fp_line
			(start 2.36982 8.148828)
			(end -1.59004 8.148828)
			(stroke
				(width 0.1)
				(type default)
			)
			(layer "F.Fab")
		)
		(fp_line
			(start -1.59004 -6.600952)
			(end 2.36982 -6.600952)
			(stroke
				(width 0.1)
				(type default)
			)
			(layer "F.Fab")
		)
		(fp_line
			(start 2.36982 -6.600952)
			(end 2.36982 8.148828)
			(stroke
				(width 0.1)
				(type default)
			)
			(layer "F.Fab")
		)
		(fp_text user "B12"
			(at 3.37947 2.503424 0)
			(unlocked yes)
			(layer "F.Fab")
			(effects
				(font
					(size 0.7874 0.5842)
					(thickness 0.1524)
				)
				(justify left)
			)
		)
		(fp_text user "A1"
			(at -3.3147 1.384554 90)
			(unlocked yes)
			(layer "F.Fab")
			(effects
				(font
					(size 0.7874 0.5842)
					(thickness 0.1524)
				)
				(justify right)
			)
		)
		(fp_text user "GH4"
			(at 3.25247 0.217424 0)
			(unlocked yes)
			(layer "F.Fab")
			(effects
				(font
					(size 0.7874 0.5842)
					(thickness 0.1524)
				)
				(justify left)
			)
		)
		(fp_text user "GH3"
			(at -2.33553 -1.433576 0)
			(unlocked yes)
			(layer "F.Fab")
			(effects
				(font
					(size 0.7874 0.5842)
					(thickness 0.1524)
				)
				(justify right)
			)
		)
		(fp_text user "GH2"
			(at 3.37947 -4.227576 0)
			(unlocked yes)
			(layer "F.Fab")
			(effects
				(font
					(size 0.7874 0.5842)
					(thickness 0.1524)
				)
				(justify left)
			)
		)
		(fp_text user "GH1"
			(at -2.58953 -6.005576 0)
			(unlocked yes)
			(layer "F.Fab")
			(effects
				(font
					(size 0.7874 0.5842)
					(thickness 0.1524)
				)
				(justify right)
			)
		)
		(fp_text user "B1"
			(at 2.276602 -7.457186 90)
			(unlocked yes)
			(layer "F.Fab")
			(effects
				(font
					(size 0.7874 0.5842)
					(thickness 0.1524)
				)
				(justify left)
			)
		)
		(fp_text user "A12"
			(at -1.175258 -7.489444 90)
			(unlocked yes)
			(layer "F.Fab")
			(effects
				(font
					(size 0.7874 0.5842)
					(thickness 0.1524)
				)
			)
		)
		(pad "A1" thru_hole circle
			(at 0 0 270)
			(size 0.6096 0.6096)
			(drill 0.4064)
			(layers "*.Cu" "*.Mask")
			(remove_unused_layers no)
			(net "SG")
			(thermal_gap 0.1905)
			(padstack
				(mode front_inner_back)
				(layer "Inner"
					(shape circle)
					(size 0.6096 0.6096)
					(clearance 0.1905)
				)
				(layer "B.Cu"
					(shape circle)
					(size 0.6096 0.6096)
				)
			)
		)
		(pad "A4" thru_hole circle
			(at 0 -0.900176 270)
			(size 0.6096 0.6096)
			(drill 0.4064)
			(layers "*.Cu" "*.Mask")
			(remove_unused_layers no)
			(net "XP5R0V_FT4232")
			(thermal_gap 0.1905)
			(padstack
				(mode front_inner_back)
				(layer "Inner"
					(shape circle)
					(size 0.6096 0.6096)
					(clearance 0.1905)
				)
				(layer "B.Cu"
					(shape circle)
					(size 0.6096 0.6096)
				)
			)
		)
		(pad "A5" thru_hole circle
			(at 0 -1.800352 270)
			(size 0.6096 0.6096)
			(drill 0.4064)
			(layers "*.Cu" "*.Mask")
			(remove_unused_layers no)
			(net "UNNAMED_524_CONNUSB14PGH4FRATH_")
			(thermal_gap 0.1905)
			(padstack
				(mode front_inner_back)
				(layer "Inner"
					(shape circle)
					(size 0.6096 0.6096)
					(clearance 0.1905)
				)
				(layer "B.Cu"
					(shape circle)
					(size 0.6096 0.6096)
				)
			)
		)
		(pad "A9" thru_hole circle
			(at 0 -4.50088 270)
			(size 0.6096 0.6096)
			(drill 0.4064)
			(layers "*.Cu" "*.Mask")
			(remove_unused_layers no)
			(net "XP5R0V_FT4232")
			(thermal_gap 0.1905)
			(padstack
				(mode front_inner_back)
				(layer "Inner"
					(shape circle)
					(size 0.6096 0.6096)
					(clearance 0.1905)
				)
				(layer "B.Cu"
					(shape circle)
					(size 0.6096 0.6096)
				)
			)
		)
		(pad "A12" thru_hole circle
			(at 0 -5.401056 270)
			(size 0.6096 0.6096)
			(drill 0.4064)
			(layers "*.Cu" "*.Mask")
			(remove_unused_layers no)
			(net "SG")
			(thermal_gap 0.1905)
			(padstack
				(mode front_inner_back)
				(layer "Inner"
					(shape circle)
					(size 0.6096 0.6096)
					(clearance 0.1905)
				)
				(layer "B.Cu"
					(shape circle)
					(size 0.6096 0.6096)
				)
			)
		)
		(pad "B1" thru_hole circle
			(at 0.77978 -4.950968 270)
			(size 0.6096 0.6096)
			(drill 0.4064)
			(layers "*.Cu" "*.Mask")
			(remove_unused_layers no)
			(net "SG")
			(thermal_gap 0.1905)
			(padstack
				(mode front_inner_back)
				(layer "Inner"
					(shape circle)
					(size 0.6096 0.6096)
					(clearance 0.1905)
				)
				(layer "B.Cu"
					(shape circle)
					(size 0.6096 0.6096)
				)
			)
		)
		(pad "B4" thru_hole circle
			(at 0.77978 -4.050792 270)
			(size 0.6096 0.6096)
			(drill 0.4064)
			(layers "*.Cu" "*.Mask")
			(remove_unused_layers no)
			(net "XP5R0V_FT4232")
			(thermal_gap 0.1905)
			(padstack
				(mode front_inner_back)
				(layer "Inner"
					(shape circle)
					(size 0.6096 0.6096)
					(clearance 0.1905)
				)
				(layer "B.Cu"
					(shape circle)
					(size 0.6096 0.6096)
				)
			)
		)
		(pad "B5" thru_hole circle
			(at 0.77978 -3.150616 270)
			(size 0.6096 0.6096)
			(drill 0.4064)
			(layers "*.Cu" "*.Mask")
			(remove_unused_layers no)
			(net "UNNAMED_524_CONNUSB14PGH4FRAT_1")
			(thermal_gap 0.1905)
			(padstack
				(mode front_inner_back)
				(layer "Inner"
					(shape circle)
					(size 0.6096 0.6096)
					(clearance 0.1905)
				)
				(layer "B.Cu"
					(shape circle)
					(size 0.6096 0.6096)
				)
			)
		)
		(pad "B9" thru_hole circle
			(at 0.77978 -0.450088 270)
			(size 0.6096 0.6096)
			(drill 0.4064)
			(layers "*.Cu" "*.Mask")
			(remove_unused_layers no)
			(net "XP5R0V_FT4232")
			(thermal_gap 0.1905)
			(padstack
				(mode front_inner_back)
				(layer "Inner"
					(shape circle)
					(size 0.6096 0.6096)
					(clearance 0.1905)
				)
				(layer "B.Cu"
					(shape circle)
					(size 0.6096 0.6096)
				)
			)
		)
		(pad "B12" thru_hole circle
			(at 0.77978 0.450088 270)
			(size 0.6096 0.6096)
			(drill 0.4064)
			(layers "*.Cu" "*.Mask")
			(remove_unused_layers no)
			(net "SG")
			(thermal_gap 0.1905)
			(padstack
				(mode front_inner_back)
				(layer "Inner"
					(shape circle)
					(size 0.6096 0.6096)
					(clearance 0.1905)
				)
				(layer "B.Cu"
					(shape circle)
					(size 0.6096 0.6096)
				)
			)
		)
		(pad "GH1" thru_hole oval
			(at -2.140204 -4.851146 270)
			(size 0.889 1.905)
			(drill oval 0.6096 1.6002)
			(layers "*.Cu" "*.Mask")
			(remove_unused_layers no)
			(net "SG")
			(thermal_gap 0.1524)
			(padstack
				(mode front_inner_back)
				(layer "Inner"
					(shape oval)
					(size 0.889 1.905)
					(clearance 0.1524)
				)
				(layer "B.Cu"
					(shape oval)
					(size 0.889 1.905)
				)
			)
		)
		(pad "GH2" thru_hole oval
			(at 2.91973 -4.851146 270)
			(size 0.889 1.905)
			(drill oval 0.6096 1.6002)
			(layers "*.Cu" "*.Mask")
			(remove_unused_layers no)
			(net "SG")
			(thermal_gap 0.1524)
			(padstack
				(mode front_inner_back)
				(layer "Inner"
					(shape oval)
					(size 0.889 1.905)
					(clearance 0.1524)
				)
				(layer "B.Cu"
					(shape oval)
					(size 0.889 1.905)
				)
			)
		)
		(pad "GH3" thru_hole oval
			(at -1.04013 -0.051054 270)
			(size 0.889 1.905)
			(drill oval 0.6096 1.6002)
			(layers "*.Cu" "*.Mask")
			(remove_unused_layers no)
			(net "SG")
			(thermal_gap 0.1524)
			(padstack
				(mode front_inner_back)
				(layer "Inner"
					(shape oval)
					(size 0.889 1.905)
					(clearance 0.1524)
				)
				(layer "B.Cu"
					(shape oval)
					(size 0.889 1.905)
				)
			)
		)
		(pad "GH4" thru_hole oval
			(at 1.81991 -0.051054 270)
			(size 0.889 1.905)
			(drill oval 0.6096 1.6002)
			(layers "*.Cu" "*.Mask")
			(remove_unused_layers no)
			(net "SG")
			(thermal_gap 0.1524)
			(padstack
				(mode front_inner_back)
				(layer "Inner"
					(shape oval)
					(size 0.889 1.905)
					(clearance 0.1524)
				)
				(layer "B.Cu"
					(shape oval)
					(size 0.889 1.905)
				)
			)
		)
	)
	(footprint ""
		(layer "F.Cu")
		(at 96.52 -53.34)
		(property "Reference" "TP182"
			(at 0 0 0)
			(layer "F.SilkS")
			(hide yes)
			(effects
				(font
					(size 1.27 1.27)
				)
			)
		)
		(property "Value" ""
			(at 0 0 0)
			(layer "F.Fab")
			(effects
				(font
					(size 1.27 1.27)
				)
			)
		)
		(property "Device Type" "TP_PIONT-TP010CT020B030_PTH-TPA"
			(at -1.341882 0.996696 0)
			(unlocked yes)
			(layer "F.Fab")
			(hide yes)
			(effects
				(font
					(size 0.7874 0.5842)
					(thickness 0.1524)
				)
				(justify left)
			)
		)
		(duplicate_pad_numbers_are_jumpers no)
		(fp_poly
			(pts
				(arc
					(start 0.889 0)
					(mid -0.889 0)
					(end 0.889 0)
				)
			)
			(stroke
				(width 0)
				(type default)
			)
			(fill no)
			(layer "B.CrtYd")
		)
		(fp_poly
			(pts
				(arc
					(start 0.889 0)
					(mid -0.889 0)
					(end 0.889 0)
				)
			)
			(stroke
				(width 0)
				(type default)
			)
			(fill no)
			(layer "F.CrtYd")
		)
		(pad "1" thru_hole circle
			(at 0 0)
			(size 0.508 0.508)
			(drill 0.254)
			(layers "*.Cu" "*.Mask")
			(remove_unused_layers no)
			(net "IO_L21N_16")
			(clearance 0.1016)
			(padstack
				(mode front_inner_back)
				(layer "Inner"
					(shape circle)
					(size 0.508 0.508)
					(clearance 0.1016)
				)
				(layer "B.Cu"
					(shape circle)
					(size 0.762 0.762)
					(clearance -0.0254)
				)
			)
		)
	)
	(footprint ""
		(layer "F.Cu")
		(at 139.5984 -99.3648 180)
		(property "Reference" "C8"
			(at 1.5494 -0.09017 0)
			(unlocked yes)
			(layer "F.SilkS")
			(effects
				(font
					(size 0.7874 0.5842)
					(thickness 0.1524)
				)
			)
		)
		(property "Value" "VAL*"
			(at 0.193548 2.13614 180)
			(unlocked yes)
			(layer "F.Fab")
			(hide yes)
			(effects
				(font
					(size 0.7874 0.5842)
					(thickness 0.1524)
				)
			)
		)
		(property "Tolerance" "TOL*"
			(at 0.216154 3.1496 180)
			(unlocked yes)
			(layer "Cmts.User")
			(hide yes)
			(effects
				(font
					(size 0.7874 0.5842)
					(thickness 0.1524)
				)
			)
		)
		(property "Device Type" "CAPACITOR-G104-0B103-EK,0.01UFA"
			(at 0.184404 1.180592 180)
			(unlocked yes)
			(layer "F.Fab")
			(hide yes)
			(effects
				(font
					(size 0.7874 0.5842)
					(thickness 0.1524)
				)
			)
		)
		(property "User Part Number" "PARTNUM*"
			(at 0.216154 4.185666 180)
			(unlocked yes)
			(layer "Cmts.User")
			(hide yes)
			(effects
				(font
					(size 0.7874 0.5842)
					(thickness 0.1524)
				)
			)
		)
		(duplicate_pad_numbers_are_jumpers no)
		(fp_line
			(start 0.671322 0.4445)
			(end -0.671322 0.4445)
			(stroke
				(width 0.1)
				(type default)
			)
			(layer "F.SilkS")
		)
		(fp_line
			(start 0.671322 -0.4445)
			(end 0.671322 0.4445)
			(stroke
				(width 0.1)
				(type default)
			)
			(layer "F.SilkS")
		)
		(fp_line
			(start -0.671322 0.4445)
			(end -0.671322 -0.4445)
			(stroke
				(width 0.1)
				(type default)
			)
			(layer "F.SilkS")
		)
		(fp_line
			(start -0.671322 -0.4445)
			(end 0.671322 -0.4445)
			(stroke
				(width 0.1)
				(type default)
			)
			(layer "F.SilkS")
		)
		(fp_rect
			(start -0.671322 0.4445)
			(end 0.671322 -0.4445)
			(stroke
				(width 0)
				(type default)
			)
			(fill no)
			(layer "F.CrtYd")
		)
		(fp_line
			(start 0.31496 0.1651)
			(end 0.31496 -0.1651)
			(stroke
				(width 0.1)
				(type default)
			)
			(layer "F.Fab")
		)
		(fp_line
			(start 0.31496 -0.1651)
			(end -0.31496 -0.1651)
			(stroke
				(width 0.1)
				(type default)
			)
			(layer "F.Fab")
		)
		(fp_line
			(start -0.31496 0.1651)
			(end 0.31496 0.1651)
			(stroke
				(width 0.1)
				(type default)
			)
			(layer "F.Fab")
		)
		(fp_line
			(start -0.31496 -0.1651)
			(end -0.31496 0.1651)
			(stroke
				(width 0.1)
				(type default)
			)
			(layer "F.Fab")
		)
		(pad "1" smd rect
			(at -0.264922 0 180)
			(size 0.3048 0.381)
			(layers "F.Cu" "F.Mask" "F.Paste")
			(net "XP12R0V_A_OV")
		)
		(pad "2" smd rect
			(at 0.264922 0 180)
			(size 0.3048 0.381)
			(layers "F.Cu" "F.Mask" "F.Paste")
			(net "SG")
		)
		(zone
			(layer "F.Cu")
			(hatch none 0.5)
			(connect_pads
				(clearance 0)
			)
			(min_thickness 0.25)
			(keepout
				(tracks allowed)
				(vias not_allowed)
				(pads allowed)
				(copperpour not_allowed)
				(footprints allowed)
			)
			(placement
				(enabled no)
				(sheetname "")
			)
			(fill
				(thermal_gap 0.5)
				(thermal_bridge_width 0.5)
				(island_removal_mode 0)
			)
			(polygon
				(pts
					(xy 139.710922 -99.5553) (xy 139.485878 -99.5553) (xy 139.485878 -99.1743) (xy 139.710922 -99.1743)
				)
			)
		)
	)
)
